(kicad_pcb
	(version 20260206)
	(generator "pcbnew")
	(generator_version "10.0")
	(general
		(thickness 1.6)
		(legacy_teardrops no)
	)
	(paper "A4")
	(title_block
		(title "03242023_DA0F0TMBIJ0_F0T_Motherboard_J_brd_V01_OCP.brd")
		(comment 1 "Grand Teton / footprints 1083-1088 of 6105")
	)
	(layers
		(0 "F.Cu" signal "TOP")
		(4 "In1.Cu" signal "GND")
		(6 "In2.Cu" signal "IN1")
		(8 "In3.Cu" signal "GND1")
		(10 "In4.Cu" signal "IN2")
		(12 "In5.Cu" signal "GND2")
		(14 "In6.Cu" signal "IN3")
		(16 "In7.Cu" signal "GND3")
		(18 "In8.Cu" signal "VCC")
		(20 "In9.Cu" signal "VCC1")
		(22 "In10.Cu" signal "GND4")
		(24 "In11.Cu" signal "IN4")
		(26 "In12.Cu" signal "GND5")
		(28 "In13.Cu" signal "IN5")
		(30 "In14.Cu" signal "GND6")
		(32 "In15.Cu" signal "IN6")
		(34 "In16.Cu" signal "GND7")
		(2 "B.Cu" signal "BOTTOM")
		(9 "F.Adhes" user "F.Adhesive")
		(11 "B.Adhes" user "B.Adhesive")
		(13 "F.Paste" user "Package Geometry/Pastemask Top")
		(15 "B.Paste" user "Package Geometry/Pastemask Bottom")
		(5 "F.SilkS" user "Ref Des/Silkscreen Top")
		(7 "B.SilkS" user "Ref Des/Silkscreen Bottom")
		(1 "F.Mask" user "Board Geometry/Soldermask Top")
		(3 "B.Mask" user "Board Geometry/Soldermask Bottom")
		(17 "Dwgs.User" user "User.Drawings")
		(19 "Cmts.User" user "User.Comments")
		(21 "Eco1.User" user "User.Eco1")
		(23 "Eco2.User" user "User.Eco2")
		(25 "Edge.Cuts" user "Board Geometry/Outline")
		(27 "Margin" user)
		(31 "F.CrtYd" user "Package Geometry/Place Bound Top")
		(29 "B.CrtYd" user "Package Geometry/Place Bound Bottom")
		(35 "F.Fab" user "Ref Des/Assembly Top")
		(33 "B.Fab" user "Ref Des/Assembly Bottom")
	)
	(footprint ""
		(layer "F.Cu")
		(at 116.561616 -244.032024 90)
		(property "Reference" "C298"
			(at 0 0 90)
			(layer "F.SilkS")
			(hide yes)
			(effects
				(font
					(size 1.27 1.27)
				)
			)
		)
		(property "Value" ""
			(at 0 0 90)
			(layer "F.Fab")
			(effects
				(font
					(size 1.27 1.27)
				)
			)
		)
		(duplicate_pad_numbers_are_jumpers no)
		(fp_line
			(start 0.7874 -0.4064)
			(end 0.7874 0.4064)
			(stroke
				(width 0.1524)
				(type default)
			)
			(layer "F.SilkS")
		)
		(fp_line
			(start -0.7874 -0.4064)
			(end 0.7874 -0.4064)
			(stroke
				(width 0.1524)
				(type default)
			)
			(layer "F.SilkS")
		)
		(fp_line
			(start 0.7874 0.4064)
			(end -0.7874 0.4064)
			(stroke
				(width 0.1524)
				(type default)
			)
			(layer "F.SilkS")
		)
		(fp_line
			(start -0.7874 0.4064)
			(end -0.7874 -0.4064)
			(stroke
				(width 0.1524)
				(type default)
			)
			(layer "F.SilkS")
		)
		(fp_line
			(start -0.12065 -0.305054)
			(end -0.12065 -0.2794)
			(stroke
				(width 0.1)
				(type default)
			)
			(layer "F.Fab")
		)
		(fp_line
			(start -0.67945 -0.305054)
			(end -0.12065 -0.305054)
			(stroke
				(width 0.1)
				(type default)
			)
			(layer "F.Fab")
		)
		(fp_line
			(start 0.67945 -0.3048)
			(end 0.67945 0.3048)
			(stroke
				(width 0.1)
				(type default)
			)
			(layer "F.Fab")
		)
		(fp_line
			(start 0.12065 -0.3048)
			(end 0.67945 -0.3048)
			(stroke
				(width 0.1)
				(type default)
			)
			(layer "F.Fab")
		)
		(fp_line
			(start 0.12065 -0.2794)
			(end 0.12065 -0.3048)
			(stroke
				(width 0.1)
				(type default)
			)
			(layer "F.Fab")
		)
		(fp_line
			(start -0.12065 -0.2794)
			(end 0.12065 -0.2794)
			(stroke
				(width 0.1)
				(type default)
			)
			(layer "F.Fab")
		)
		(fp_line
			(start 0.120396 0.2794)
			(end -0.12065 0.2794)
			(stroke
				(width 0.1)
				(type default)
			)
			(layer "F.Fab")
		)
		(fp_line
			(start -0.12065 0.2794)
			(end -0.12065 0.3048)
			(stroke
				(width 0.1)
				(type default)
			)
			(layer "F.Fab")
		)
		(fp_line
			(start 0.67945 0.3048)
			(end 0.120396 0.3048)
			(stroke
				(width 0.1)
				(type default)
			)
			(layer "F.Fab")
		)
		(fp_line
			(start 0.120396 0.3048)
			(end 0.120396 0.2794)
			(stroke
				(width 0.1)
				(type default)
			)
			(layer "F.Fab")
		)
		(fp_line
			(start -0.12065 0.3048)
			(end -0.67945 0.3048)
			(stroke
				(width 0.1)
				(type default)
			)
			(layer "F.Fab")
		)
		(fp_line
			(start -0.67945 0.3048)
			(end -0.67945 -0.305054)
			(stroke
				(width 0.1)
				(type default)
			)
			(layer "F.Fab")
		)
		(pad "1" smd circle
			(at -0.40005 0 90)
			(size 0 0)
			(layers "F.Cu" "F.Mask" "F.Paste")
			(net "PVCCIN_CPU1")
		)
		(pad "2" smd circle
			(at 0.40005 0 90)
			(size 0 0)
			(layers "F.Cu" "F.Mask" "F.Paste")
			(net "GND")
		)
	)
	(footprint ""
		(layer "F.Cu")
		(at 24.069802 -409.402534 180)
		(property "Reference" "C1988"
			(at 0 0 180)
			(layer "F.SilkS")
			(hide yes)
			(effects
				(font
					(size 1.27 1.27)
				)
			)
		)
		(property "Value" ""
			(at 0 0 180)
			(layer "F.Fab")
			(effects
				(font
					(size 1.27 1.27)
				)
			)
		)
		(duplicate_pad_numbers_are_jumpers no)
		(fp_line
			(start 0.7874 0.4064)
			(end -0.7874 0.4064)
			(stroke
				(width 0.1524)
				(type default)
			)
			(layer "F.SilkS")
		)
		(fp_line
			(start 0.7874 -0.4064)
			(end 0.7874 0.4064)
			(stroke
				(width 0.1524)
				(type default)
			)
			(layer "F.SilkS")
		)
		(fp_line
			(start -0.7874 0.4064)
			(end -0.7874 -0.4064)
			(stroke
				(width 0.1524)
				(type default)
			)
			(layer "F.SilkS")
		)
		(fp_line
			(start -0.7874 -0.4064)
			(end 0.7874 -0.4064)
			(stroke
				(width 0.1524)
				(type default)
			)
			(layer "F.SilkS")
		)
		(fp_line
			(start 0.67945 0.3048)
			(end 0.120396 0.3048)
			(stroke
				(width 0.1)
				(type default)
			)
			(layer "F.Fab")
		)
		(fp_line
			(start 0.67945 -0.3048)
			(end 0.67945 0.3048)
			(stroke
				(width 0.1)
				(type default)
			)
			(layer "F.Fab")
		)
		(fp_line
			(start 0.12065 -0.2794)
			(end 0.12065 -0.3048)
			(stroke
				(width 0.1)
				(type default)
			)
			(layer "F.Fab")
		)
		(fp_line
			(start 0.12065 -0.3048)
			(end 0.67945 -0.3048)
			(stroke
				(width 0.1)
				(type default)
			)
			(layer "F.Fab")
		)
		(fp_line
			(start 0.120396 0.3048)
			(end 0.120396 0.2794)
			(stroke
				(width 0.1)
				(type default)
			)
			(layer "F.Fab")
		)
		(fp_line
			(start 0.120396 0.2794)
			(end -0.12065 0.2794)
			(stroke
				(width 0.1)
				(type default)
			)
			(layer "F.Fab")
		)
		(fp_line
			(start -0.12065 0.3048)
			(end -0.67945 0.3048)
			(stroke
				(width 0.1)
				(type default)
			)
			(layer "F.Fab")
		)
		(fp_line
			(start -0.12065 0.2794)
			(end -0.12065 0.3048)
			(stroke
				(width 0.1)
				(type default)
			)
			(layer "F.Fab")
		)
		(fp_line
			(start -0.12065 -0.2794)
			(end 0.12065 -0.2794)
			(stroke
				(width 0.1)
				(type default)
			)
			(layer "F.Fab")
		)
		(fp_line
			(start -0.12065 -0.305054)
			(end -0.12065 -0.2794)
			(stroke
				(width 0.1)
				(type default)
			)
			(layer "F.Fab")
		)
		(fp_line
			(start -0.67945 0.3048)
			(end -0.67945 -0.305054)
			(stroke
				(width 0.1)
				(type default)
			)
			(layer "F.Fab")
		)
		(fp_line
			(start -0.67945 -0.305054)
			(end -0.12065 -0.305054)
			(stroke
				(width 0.1)
				(type default)
			)
			(layer "F.Fab")
		)
		(pad "1" smd circle
			(at -0.40005 0 180)
			(size 0 0)
			(layers "F.Cu" "F.Mask" "F.Paste")
			(net "GPU_FPGA_EROT_FATALERR_ISO_N")
		)
		(pad "2" smd circle
			(at 0.40005 0 180)
			(size 0 0)
			(layers "F.Cu" "F.Mask" "F.Paste")
			(net "GND")
		)
	)
	(footprint ""
		(layer "F.Cu")
		(at 153.13914 -119.001032 90)
		(property "Reference" "Q50"
			(at 0.792226 -2.610104 0)
			(unlocked yes)
			(layer "F.SilkS")
			(effects
				(font
					(size 0.7874 0.5842)
					(thickness 0.1524)
				)
			)
		)
		(property "Value" ""
			(at 0 0 90)
			(layer "F.Fab")
			(effects
				(font
					(size 1.27 1.27)
				)
			)
		)
		(duplicate_pad_numbers_are_jumpers no)
		(fp_line
			(start 1.332738 -1.100074)
			(end 1.332738 1.100074)
			(stroke
				(width 0.1524)
				(type default)
			)
			(layer "F.SilkS")
		)
		(fp_line
			(start 0.4826 -1.100074)
			(end 1.332738 -1.100074)
			(stroke
				(width 0.1524)
				(type default)
			)
			(layer "F.SilkS")
		)
		(fp_line
			(start -0.4826 -1.100074)
			(end 0 -0.541274)
			(stroke
				(width 0.1524)
				(type default)
			)
			(layer "F.SilkS")
		)
		(fp_line
			(start -1.332738 -1.100074)
			(end -0.4826 -1.100074)
			(stroke
				(width 0.1524)
				(type default)
			)
			(layer "F.SilkS")
		)
		(fp_line
			(start 0 -0.541274)
			(end 0.4826 -1.100074)
			(stroke
				(width 0.1524)
				(type default)
			)
			(layer "F.SilkS")
		)
		(fp_line
			(start 1.332738 1.100074)
			(end -1.332738 1.100074)
			(stroke
				(width 0.1524)
				(type default)
			)
			(layer "F.SilkS")
		)
		(fp_line
			(start -1.332738 1.100074)
			(end -1.332738 -1.100074)
			(stroke
				(width 0.1524)
				(type default)
			)
			(layer "F.SilkS")
		)
		(fp_poly
			(pts
				(xy -1.442466 -2.226056) (xy -0.74041 -2.226056) (xy -1.091438 -1.524)
			)
			(stroke
				(width 0)
				(type default)
			)
			(fill yes)
			(layer "F.SilkS")
		)
		(fp_line
			(start 0.674878 -1.100074)
			(end 0.674878 1.100074)
			(stroke
				(width 0.1)
				(type default)
			)
			(layer "F.Fab")
		)
		(fp_line
			(start -0.674878 -1.100074)
			(end 0.674878 -1.100074)
			(stroke
				(width 0.1)
				(type default)
			)
			(layer "F.Fab")
		)
		(fp_line
			(start 0.674878 1.100074)
			(end -0.674878 1.100074)
			(stroke
				(width 0.1)
				(type default)
			)
			(layer "F.Fab")
		)
		(fp_line
			(start -0.674878 1.100074)
			(end -0.674878 -1.100074)
			(stroke
				(width 0.1)
				(type default)
			)
			(layer "F.Fab")
		)
		(fp_poly
			(pts
				(xy -2.2352 -0.298958) (xy -2.2352 -1.001014) (xy -1.533144 -0.649986)
			)
			(stroke
				(width 0)
				(type default)
			)
			(fill yes)
			(layer "F.Fab")
		)
		(pad "1" smd rect
			(at -0.94996 -0.649986 180)
			(size 0.4318 0.508)
			(layers "F.Cu" "F.Mask" "F.Paste")
			(net "GND")
		)
		(pad "2" smd rect
			(at -0.94996 0 180)
			(size 0.4318 0.508)
			(layers "F.Cu" "F.Mask" "F.Paste")
			(net "PWRGD_P5V_AUX")
		)
		(pad "3" smd rect
			(at -0.94996 0.649986 180)
			(size 0.4318 0.508)
			(layers "F.Cu" "F.Mask" "F.Paste")
			(net "PWRGD_P5V_AUX_R2")
		)
		(pad "4" smd rect
			(at 0.94996 0.649986 180)
			(size 0.4318 0.508)
			(layers "F.Cu" "F.Mask" "F.Paste")
			(net "GND")
		)
		(pad "5" smd rect
			(at 0.94996 0 180)
			(size 0.4318 0.508)
			(layers "F.Cu" "F.Mask" "F.Paste")
			(net "PWRGD_P5V_AUX_R1")
		)
		(pad "6" smd rect
			(at 0.94996 -0.649986 180)
			(size 0.4318 0.508)
			(layers "F.Cu" "F.Mask" "F.Paste")
			(net "PWRGD_P5V_AUX_R1")
		)
	)
	(footprint ""
		(layer "F.Cu")
		(at 431.989992 -381.218948 180)
		(property "Reference" "R2834"
			(at 0 0 180)
			(layer "F.SilkS")
			(hide yes)
			(effects
				(font
					(size 1.27 1.27)
				)
			)
		)
		(property "Value" ""
			(at 0 0 180)
			(layer "F.Fab")
			(effects
				(font
					(size 1.27 1.27)
				)
			)
		)
		(duplicate_pad_numbers_are_jumpers no)
		(fp_line
			(start 0.7874 0.4064)
			(end -0.7874 0.4064)
			(stroke
				(width 0.1524)
				(type default)
			)
			(layer "F.SilkS")
		)
		(fp_line
			(start 0.7874 -0.4064)
			(end 0.7874 0.4064)
			(stroke
				(width 0.1524)
				(type default)
			)
			(layer "F.SilkS")
		)
		(fp_line
			(start -0.7874 0.4064)
			(end -0.7874 -0.4064)
			(stroke
				(width 0.1524)
				(type default)
			)
			(layer "F.SilkS")
		)
		(fp_line
			(start -0.7874 -0.4064)
			(end 0.7874 -0.4064)
			(stroke
				(width 0.1524)
				(type default)
			)
			(layer "F.SilkS")
		)
		(fp_line
			(start 0.67945 0.3048)
			(end 0.120396 0.3048)
			(stroke
				(width 0.1)
				(type default)
			)
			(layer "F.Fab")
		)
		(fp_line
			(start 0.67945 -0.3048)
			(end 0.67945 0.3048)
			(stroke
				(width 0.1)
				(type default)
			)
			(layer "F.Fab")
		)
		(fp_line
			(start 0.12065 -0.2794)
			(end 0.12065 -0.3048)
			(stroke
				(width 0.1)
				(type default)
			)
			(layer "F.Fab")
		)
		(fp_line
			(start 0.12065 -0.3048)
			(end 0.67945 -0.3048)
			(stroke
				(width 0.1)
				(type default)
			)
			(layer "F.Fab")
		)
		(fp_line
			(start 0.120396 0.3048)
			(end 0.120396 0.2794)
			(stroke
				(width 0.1)
				(type default)
			)
			(layer "F.Fab")
		)
		(fp_line
			(start 0.120396 0.2794)
			(end -0.12065 0.2794)
			(stroke
				(width 0.1)
				(type default)
			)
			(layer "F.Fab")
		)
		(fp_line
			(start -0.12065 0.3048)
			(end -0.67945 0.3048)
			(stroke
				(width 0.1)
				(type default)
			)
			(layer "F.Fab")
		)
		(fp_line
			(start -0.12065 0.2794)
			(end -0.12065 0.3048)
			(stroke
				(width 0.1)
				(type default)
			)
			(layer "F.Fab")
		)
		(fp_line
			(start -0.12065 -0.2794)
			(end 0.12065 -0.2794)
			(stroke
				(width 0.1)
				(type default)
			)
			(layer "F.Fab")
		)
		(fp_line
			(start -0.12065 -0.305054)
			(end -0.12065 -0.2794)
			(stroke
				(width 0.1)
				(type default)
			)
			(layer "F.Fab")
		)
		(fp_line
			(start -0.67945 0.3048)
			(end -0.67945 -0.305054)
			(stroke
				(width 0.1)
				(type default)
			)
			(layer "F.Fab")
		)
		(fp_line
			(start -0.67945 -0.305054)
			(end -0.12065 -0.305054)
			(stroke
				(width 0.1)
				(type default)
			)
			(layer "F.Fab")
		)
		(pad "1" smd circle
			(at -0.40005 0 180)
			(size 0 0)
			(layers "F.Cu" "F.Mask" "F.Paste")
			(net "P3V3_AUX")
		)
		(pad "2" smd circle
			(at 0.40005 0 180)
			(size 0 0)
			(layers "F.Cu" "F.Mask" "F.Paste")
			(net "RST_BMC_FROM_SWB")
		)
	)
	(footprint ""
		(layer "F.Cu")
		(at 299.02023 -47.288196)
		(property "Reference" "R2972"
			(at 0 0 0)
			(layer "F.SilkS")
			(hide yes)
			(effects
				(font
					(size 1.27 1.27)
				)
			)
		)
		(property "Value" ""
			(at 0 0 0)
			(layer "F.Fab")
			(effects
				(font
					(size 1.27 1.27)
				)
			)
		)
		(duplicate_pad_numbers_are_jumpers no)
		(fp_line
			(start -0.7874 -0.4064)
			(end 0.7874 -0.4064)
			(stroke
				(width 0.1524)
				(type default)
			)
			(layer "F.SilkS")
		)
		(fp_line
			(start -0.7874 0.4064)
			(end -0.7874 -0.4064)
			(stroke
				(width 0.1524)
				(type default)
			)
			(layer "F.SilkS")
		)
		(fp_line
			(start 0.7874 -0.4064)
			(end 0.7874 0.4064)
			(stroke
				(width 0.1524)
				(type default)
			)
			(layer "F.SilkS")
		)
		(fp_line
			(start 0.7874 0.4064)
			(end -0.7874 0.4064)
			(stroke
				(width 0.1524)
				(type default)
			)
			(layer "F.SilkS")
		)
		(fp_line
			(start -0.67945 -0.305054)
			(end -0.12065 -0.305054)
			(stroke
				(width 0.1)
				(type default)
			)
			(layer "F.Fab")
		)
		(fp_line
			(start -0.67945 0.3048)
			(end -0.67945 -0.305054)
			(stroke
				(width 0.1)
				(type default)
			)
			(layer "F.Fab")
		)
		(fp_line
			(start -0.12065 -0.305054)
			(end -0.12065 -0.2794)
			(stroke
				(width 0.1)
				(type default)
			)
			(layer "F.Fab")
		)
		(fp_line
			(start -0.12065 -0.2794)
			(end 0.12065 -0.2794)
			(stroke
				(width 0.1)
				(type default)
			)
			(layer "F.Fab")
		)
		(fp_line
			(start -0.12065 0.2794)
			(end -0.12065 0.3048)
			(stroke
				(width 0.1)
				(type default)
			)
			(layer "F.Fab")
		)
		(fp_line
			(start -0.12065 0.3048)
			(end -0.67945 0.3048)
			(stroke
				(width 0.1)
				(type default)
			)
			(layer "F.Fab")
		)
		(fp_line
			(start 0.120396 0.2794)
			(end -0.12065 0.2794)
			(stroke
				(width 0.1)
				(type default)
			)
			(layer "F.Fab")
		)
		(fp_line
			(start 0.120396 0.3048)
			(end 0.120396 0.2794)
			(stroke
				(width 0.1)
				(type default)
			)
			(layer "F.Fab")
		)
		(fp_line
			(start 0.12065 -0.3048)
			(end 0.67945 -0.3048)
			(stroke
				(width 0.1)
				(type default)
			)
			(layer "F.Fab")
		)
		(fp_line
			(start 0.12065 -0.2794)
			(end 0.12065 -0.3048)
			(stroke
				(width 0.1)
				(type default)
			)
			(layer "F.Fab")
		)
		(fp_line
			(start 0.67945 -0.3048)
			(end 0.67945 0.3048)
			(stroke
				(width 0.1)
				(type default)
			)
			(layer "F.Fab")
		)
		(fp_line
			(start 0.67945 0.3048)
			(end 0.120396 0.3048)
			(stroke
				(width 0.1)
				(type default)
			)
			(layer "F.Fab")
		)
		(pad "1" smd circle
			(at -0.40005 0)
			(size 0 0)
			(layers "F.Cu" "F.Mask" "F.Paste")
			(net "P1V05_PCH_AUX")
		)
		(pad "2" smd circle
			(at 0.40005 0)
			(size 0 0)
			(layers "F.Cu" "F.Mask" "F.Paste")
			(net "FAB_REV_ID2")
		)
	)
	(footprint ""
		(layer "F.Cu")
		(at 179.360068 -397.188182)
		(property "Reference" "PR3930"
			(at 0 0 0)
			(layer "F.SilkS")
			(hide yes)
			(effects
				(font
					(size 1.27 1.27)
				)
			)
		)
		(property "Value" ""
			(at 0 0 0)
			(layer "F.Fab")
			(effects
				(font
					(size 1.27 1.27)
				)
			)
		)
		(duplicate_pad_numbers_are_jumpers no)
		(fp_line
			(start -0.7874 -0.4064)
			(end 0.7874 -0.4064)
			(stroke
				(width 0.1524)
				(type default)
			)
			(layer "F.SilkS")
		)
		(fp_line
			(start -0.7874 0.4064)
			(end -0.7874 -0.4064)
			(stroke
				(width 0.1524)
				(type default)
			)
			(layer "F.SilkS")
		)
		(fp_line
			(start 0.7874 -0.4064)
			(end 0.7874 0.4064)
			(stroke
				(width 0.1524)
				(type default)
			)
			(layer "F.SilkS")
		)
		(fp_line
			(start 0.7874 0.4064)
			(end -0.7874 0.4064)
			(stroke
				(width 0.1524)
				(type default)
			)
			(layer "F.SilkS")
		)
		(fp_line
			(start -0.67945 -0.305054)
			(end -0.12065 -0.305054)
			(stroke
				(width 0.1)
				(type default)
			)
			(layer "F.Fab")
		)
		(fp_line
			(start -0.67945 0.3048)
			(end -0.67945 -0.305054)
			(stroke
				(width 0.1)
				(type default)
			)
			(layer "F.Fab")
		)
		(fp_line
			(start -0.12065 -0.305054)
			(end -0.12065 -0.2794)
			(stroke
				(width 0.1)
				(type default)
			)
			(layer "F.Fab")
		)
		(fp_line
			(start -0.12065 -0.2794)
			(end 0.12065 -0.2794)
			(stroke
				(width 0.1)
				(type default)
			)
			(layer "F.Fab")
		)
		(fp_line
			(start -0.12065 0.2794)
			(end -0.12065 0.3048)
			(stroke
				(width 0.1)
				(type default)
			)
			(layer "F.Fab")
		)
		(fp_line
			(start -0.12065 0.3048)
			(end -0.67945 0.3048)
			(stroke
				(width 0.1)
				(type default)
			)
			(layer "F.Fab")
		)
		(fp_line
			(start 0.120396 0.2794)
			(end -0.12065 0.2794)
			(stroke
				(width 0.1)
				(type default)
			)
			(layer "F.Fab")
		)
		(fp_line
			(start 0.120396 0.3048)
			(end 0.120396 0.2794)
			(stroke
				(width 0.1)
				(type default)
			)
			(layer "F.Fab")
		)
		(fp_line
			(start 0.12065 -0.3048)
			(end 0.67945 -0.3048)
			(stroke
				(width 0.1)
				(type default)
			)
			(layer "F.Fab")
		)
		(fp_line
			(start 0.12065 -0.2794)
			(end 0.12065 -0.3048)
			(stroke
				(width 0.1)
				(type default)
			)
			(layer "F.Fab")
		)
		(fp_line
			(start 0.67945 -0.3048)
			(end 0.67945 0.3048)
			(stroke
				(width 0.1)
				(type default)
			)
			(layer "F.Fab")
		)
		(fp_line
			(start 0.67945 0.3048)
			(end 0.120396 0.3048)
			(stroke
				(width 0.1)
				(type default)
			)
			(layer "F.Fab")
		)
		(pad "1" smd circle
			(at -0.40005 0)
			(size 0 0)
			(layers "F.Cu" "F.Mask" "F.Paste")
			(net "AGND_HSC")
		)
		(pad "2" smd circle
			(at 0.40005 0)
			(size 0 0)
			(layers "F.Cu" "F.Mask" "F.Paste")
			(net "HSC_ADDR")
		)
	)
)
